# S9S_MB_2U (Grand Teton) — schematic netlist excerpt (pin names and nets, part order shuffled) for the footprints in the layout excerpt that follows; sources: Cadence DE-HDL packaged netlist, KiCad conversion of 03242023_DA0F0TMBIJ0_F0T_Motherboard_J_brd_V01_OCP.brd

J78  PICOPROBE_BXA  DELTA-L 4.0 EMPTY  pkg TRIANG_LAUNCH_3PXB  page 308
  \1_p\  = DELTA_L_85_10INCH_IN2_DP
  \2_n\  = DELTA_L_85_10INCH_IN2_DN
  \3_g\  = DELTA_L_GND_1

(kicad_pcb
	(version 20260206)
	(generator "pcbnew")
	(generator_version "10.0")
	(general
		(thickness 1.6)
		(legacy_teardrops no)
	)
	(paper "A4")
	(title_block
		(title "03242023_DA0F0TMBIJ0_F0T_Motherboard_J_brd_V01_OCP.brd")
		(comment 1 "Grand Teton / footprints 2334-2334 of 6105")
	)
	(layers
		(0 "F.Cu" signal "TOP")
		(4 "In1.Cu" signal "GND")
		(6 "In2.Cu" signal "IN1")
		(8 "In3.Cu" signal "GND1")
		(10 "In4.Cu" signal "IN2")
		(12 "In5.Cu" signal "GND2")
		(14 "In6.Cu" signal "IN3")
		(16 "In7.Cu" signal "GND3")
		(18 "In8.Cu" signal "VCC")
		(20 "In9.Cu" signal "VCC1")
		(22 "In10.Cu" signal "GND4")
		(24 "In11.Cu" signal "IN4")
		(26 "In12.Cu" signal "GND5")
		(28 "In13.Cu" signal "IN5")
		(30 "In14.Cu" signal "GND6")
		(32 "In15.Cu" signal "IN6")
		(34 "In16.Cu" signal "GND7")
		(2 "B.Cu" signal "BOTTOM")
		(9 "F.Adhes" user "F.Adhesive")
		(11 "B.Adhes" user "B.Adhesive")
		(13 "F.Paste" user "Package Geometry/Pastemask Top")
		(15 "B.Paste" user "Package Geometry/Pastemask Bottom")
		(5 "F.SilkS" user "Ref Des/Silkscreen Top")
		(7 "B.SilkS" user "Ref Des/Silkscreen Bottom")
		(1 "F.Mask" user "Board Geometry/Soldermask Top")
		(3 "B.Mask" user "Board Geometry/Soldermask Bottom")
		(17 "Dwgs.User" user "User.Drawings")
		(19 "Cmts.User" user "User.Comments")
		(21 "Eco1.User" user "User.Eco1")
		(23 "Eco2.User" user "User.Eco2")
		(25 "Edge.Cuts" user "Board Geometry/Outline")
		(27 "Margin" user)
		(31 "F.CrtYd" user "Package Geometry/Place Bound Top")
		(29 "B.CrtYd" user "Package Geometry/Place Bound Bottom")
		(35 "F.Fab" user "Ref Des/Assembly Top")
		(33 "B.Fab" user "Ref Des/Assembly Bottom")
	)
	(footprint ""
		(layer "F.Cu")
		(at 260.731508 5.463794)
		(property "Reference" "J78"
			(at -4.164838 1.013206 90)
			(unlocked yes)
			(layer "F.SilkS")
			(effects
				(font
					(size 0.7874 0.5842)
					(thickness 0.1524)
				)
				(justify left)
			)
		)
		(property "Value" ""
			(at 0 0 0)
			(layer "F.Fab")
			(effects
				(font
					(size 1.27 1.27)
				)
			)
		)
		(duplicate_pad_numbers_are_jumpers no)
		(fp_line
			(start -1.2192 -2.1082)
			(end 1.2192 -2.1082)
			(stroke
				(width 0.1524)
				(type default)
			)
			(layer "F.SilkS")
		)
		(fp_line
			(start -1.2192 2.1082)
			(end -1.2192 -2.1082)
			(stroke
				(width 0.1524)
				(type default)
			)
			(layer "F.SilkS")
		)
		(fp_line
			(start 1.2192 -2.1082)
			(end 1.2192 2.1082)
			(stroke
				(width 0.1524)
				(type default)
			)
			(layer "F.SilkS")
		)
		(fp_line
			(start 1.2192 2.1082)
			(end -1.2192 2.1082)
			(stroke
				(width 0.1524)
				(type default)
			)
			(layer "F.SilkS")
		)
		(pad "" np_thru_hole circle
			(at -2.8829 -1.27 270)
			(size 1.0414 1.0414)
			(drill 1.0414)
			(layers "*.Cu" "*.Mask")
			(clearance 0.381)
			(thermal_gap 0.381)
		)
		(pad "" np_thru_hole circle
			(at -2.8829 1.27 270)
			(size 1.0414 1.0414)
			(drill 1.0414)
			(layers "*.Cu" "*.Mask")
			(clearance 0.381)
			(thermal_gap 0.381)
		)
		(pad "" np_thru_hole circle
			(at 3.4671 -1.27 270)
			(size 1.0414 1.0414)
			(drill 1.0414)
			(layers "*.Cu" "*.Mask")
			(clearance 0.381)
			(thermal_gap 0.381)
		)
		(pad "" np_thru_hole circle
			(at 3.4671 1.27 270)
			(size 1.0414 1.0414)
			(drill 1.0414)
			(layers "*.Cu" "*.Mask")
			(clearance 0.381)
			(thermal_gap 0.381)
		)
		(pad "1" smd rect
			(at 0.8255 -0.249936 270)
			(size 0.3048 0.508)
			(layers "F.Cu" "F.Mask" "F.Paste")
			(net "DELTA_L_85_10INCH_IN2_DP")
		)
		(pad "2" smd rect
			(at 0.8255 0.249936 270)
			(size 0.3048 0.508)
			(layers "F.Cu" "F.Mask" "F.Paste")
			(net "DELTA_L_85_10INCH_IN2_DN")
		)
		(pad "3" smd circle
			(at 0 0)
			(size 0 0)
			(layers "F.Cu" "F.Mask" "F.Paste")
			(net "DELTA_L_GND_1")
		)
		(zone
			(layer "F.Cu")
			(hatch none 0.5)
			(connect_pads
				(clearance 0)
			)
			(min_thickness 0.25)
			(keepout
				(tracks not_allowed)
				(vias allowed)
				(pads allowed)
				(copperpour not_allowed)
				(footprints allowed)
			)
			(placement
				(enabled no)
				(sheetname "")
			)
			(fill
				(thermal_gap 0.5)
				(thermal_bridge_width 0.5)
				(island_removal_mode 0)
			)
			(polygon
				(pts
					(xy 261.849108 4.915154) (xy 261.849108 5.010658) (xy 261.252208 5.010658) (xy 261.252208 5.417058)
					(xy 261.849108 5.417058) (xy 261.849108 5.51053) (xy 261.252208 5.51053) (xy 261.252208 5.91693)
					(xy 261.849108 5.91693) (xy 261.849108 6.012434) (xy 261.150608 6.012434) (xy 261.150608 4.915154)
				)
			)
		)
		(zone
			(layers "F.Cu" "B.Cu" "In1.Cu" "In2.Cu" "In3.Cu" "In4.Cu" "In5.Cu" "In6.Cu"
				"In7.Cu" "In8.Cu" "In9.Cu" "In10.Cu" "In11.Cu" "In12.Cu" "In13.Cu" "In14.Cu"
				"In15.Cu" "In16.Cu"
			)
			(hatch none 0.5)
			(connect_pads
				(clearance 0)
			)
			(min_thickness 0.25)
			(keepout
				(tracks not_allowed)
				(vias allowed)
				(pads allowed)
				(copperpour not_allowed)
				(footprints allowed)
			)
			(placement
				(enabled no)
				(sheetname "")
			)
			(fill
				(thermal_gap 0.5)
				(thermal_bridge_width 0.5)
				(island_removal_mode 0)
			)
			(polygon
				(pts
					(arc
						(start 258.775708 4.193794)
						(mid 256.921508 4.193794)
						(end 258.775708 4.193794)
					)
				)
			)
		)
		(zone
			(layers "F.Cu" "B.Cu" "In1.Cu" "In2.Cu" "In3.Cu" "In4.Cu" "In5.Cu" "In6.Cu"
				"In7.Cu" "In8.Cu" "In9.Cu" "In10.Cu" "In11.Cu" "In12.Cu" "In13.Cu" "In14.Cu"
				"In15.Cu" "In16.Cu"
			)
			(hatch none 0.5)
			(connect_pads
				(clearance 0)
			)
			(min_thickness 0.25)
			(keepout
				(tracks not_allowed)
				(vias allowed)
				(pads allowed)
				(copperpour not_allowed)
				(footprints allowed)
			)
			(placement
				(enabled no)
				(sheetname "")
			)
			(fill
				(thermal_gap 0.5)
				(thermal_bridge_width 0.5)
				(island_removal_mode 0)
			)
			(polygon
				(pts
					(arc
						(start 258.775708 6.733794)
						(mid 256.921508 6.733794)
						(end 258.775708 6.733794)
					)
				)
			)
		)
		(zone
			(layers "F.Cu" "B.Cu" "In1.Cu" "In2.Cu" "In3.Cu" "In4.Cu" "In5.Cu" "In6.Cu"
				"In7.Cu" "In8.Cu" "In9.Cu" "In10.Cu" "In11.Cu" "In12.Cu" "In13.Cu" "In14.Cu"
				"In15.Cu" "In16.Cu"
			)
			(hatch none 0.5)
			(connect_pads
				(clearance 0)
			)
			(min_thickness 0.25)
			(keepout
				(tracks not_allowed)
				(vias allowed)
				(pads allowed)
				(copperpour not_allowed)
				(footprints allowed)
			)
			(placement
				(enabled no)
				(sheetname "")
			)
			(fill
				(thermal_gap 0.5)
				(thermal_bridge_width 0.5)
				(island_removal_mode 0)
			)
			(polygon
				(pts
					(arc
						(start 265.125708 4.193794)
						(mid 263.271508 4.193794)
						(end 265.125708 4.193794)
					)
				)
			)
		)
		(zone
			(layers "F.Cu" "B.Cu" "In1.Cu" "In2.Cu" "In3.Cu" "In4.Cu" "In5.Cu" "In6.Cu"
				"In7.Cu" "In8.Cu" "In9.Cu" "In10.Cu" "In11.Cu" "In12.Cu" "In13.Cu" "In14.Cu"
				"In15.Cu" "In16.Cu"
			)
			(hatch none 0.5)
			(connect_pads
				(clearance 0)
			)
			(min_thickness 0.25)
			(keepout
				(tracks not_allowed)
				(vias allowed)
				(pads allowed)
				(copperpour not_allowed)
				(footprints allowed)
			)
			(placement
				(enabled no)
				(sheetname "")
			)
			(fill
				(thermal_gap 0.5)
				(thermal_bridge_width 0.5)
				(island_removal_mode 0)
			)
			(polygon
				(pts
					(arc
						(start 265.125708 6.733794)
						(mid 263.271508 6.733794)
						(end 265.125708 6.733794)
					)
				)
			)
		)
	)
)
